(kicad_pcb
	(version 20260206)
	(generator "pcbnew")
	(generator_version "10.0")
	(general
		(thickness 1.6)
		(legacy_teardrops no)
	)
	(paper "A4")
	(title_block
		(title "15969-1a.1015WZS0858.brd")
		(comment 1 "Tioga Pass / footprints 151-157 of 295")
	)
	(layers
		(0 "F.Cu" signal "TOP")
		(4 "In1.Cu" signal "L2GND")
		(6 "In2.Cu" signal "L3")
		(8 "In3.Cu" signal "L4")
		(10 "In4.Cu" signal "L5GND")
		(2 "B.Cu" signal "BOTTOM")
		(9 "F.Adhes" user "F.Adhesive")
		(11 "B.Adhes" user "B.Adhesive")
		(13 "F.Paste" user "Package Geometry/Pastemask Top")
		(15 "B.Paste" user "Package Geometry/Pastemask Bottom")
		(5 "F.SilkS" user "Ref Des/Silkscreen Top")
		(7 "B.SilkS" user "Ref Des/Silkscreen Bottom")
		(1 "F.Mask" user "Board Geometry/Soldermask Top")
		(3 "B.Mask" user "Board Geometry/Soldermask Bottom")
		(17 "Dwgs.User" user "User.Drawings")
		(19 "Cmts.User" user "User.Comments")
		(21 "Eco1.User" user "User.Eco1")
		(23 "Eco2.User" user "User.Eco2")
		(25 "Edge.Cuts" user "Board Geometry/Outline")
		(27 "Margin" user)
		(31 "F.CrtYd" user "Package Geometry/Place Bound Top")
		(29 "B.CrtYd" user "Package Geometry/Place Bound Bottom")
		(35 "F.Fab" user "Ref Des/Assembly Top")
		(33 "B.Fab" user "Ref Des/Assembly Bottom")
	)
	(footprint ""
		(layer "F.Cu")
		(at 93.5482 -19.9136 90)
		(property "Reference" "C34"
			(at 0 0 90)
			(layer "F.SilkS")
			(hide yes)
			(effects
				(font
					(size 1.27 1.27)
				)
			)
		)
		(property "Value" "SCD1U16V2KX-3GP"
			(at 1.1811 -2.7051 90)
			(unlocked yes)
			(layer "F.Fab")
			(hide yes)
			(effects
				(font
					(size 1.016 1.016)
					(thickness 0.1524)
				)
			)
		)
		(property "Device Type" "C402H22"
			(at 1.1811 -4.2291 90)
			(unlocked yes)
			(layer "F.Fab")
			(hide yes)
			(effects
				(font
					(size 1.016 1.016)
					(thickness 0.1524)
				)
			)
		)
		(duplicate_pad_numbers_are_jumpers no)
		(fp_rect
			(start -0.4318 0.9525)
			(end 0.4318 -0.9525)
			(stroke
				(width 0)
				(type default)
			)
			(fill no)
			(layer "F.CrtYd")
		)
		(fp_rect
			(start -0.4318 0.9525)
			(end 0.4318 -0.9525)
			(stroke
				(width 0)
				(type default)
			)
			(fill no)
			(layer "F.Fab")
		)
		(pad "1" smd custom
			(at 0 -0.4445 90)
			(size 0.1524 0.1524)
			(layers "F.Cu" "F.Mask" "F.Paste")
			(net "P3V3_STBY")
			(options
				(clearance outline)
				(anchor circle)
			)
			(primitives
				(gr_poly
					(pts
						(arc
							(start 0.3048 -0.2032)
							(mid 0.275042 -0.275042)
							(end 0.2032 -0.3048)
						)
						(arc
							(start -0.2032 -0.3048)
							(mid -0.275042 -0.275042)
							(end -0.3048 -0.2032)
						)
						(arc
							(start -0.3048 0.2032)
							(mid -0.275042 0.275042)
							(end -0.2032 0.3048)
						)
						(arc
							(start 0.2032 0.3048)
							(mid 0.275042 0.275042)
							(end 0.3048 0.2032)
						)
					)
					(width 0)
					(fill yes)
				)
			)
		)
		(pad "2" smd custom
			(at 0 0.4445 90)
			(size 0.1524 0.1524)
			(layers "F.Cu" "F.Mask" "F.Paste")
			(net "GND")
			(options
				(clearance outline)
				(anchor circle)
			)
			(primitives
				(gr_poly
					(pts
						(arc
							(start 0.3048 -0.2032)
							(mid 0.275042 -0.275042)
							(end 0.2032 -0.3048)
						)
						(arc
							(start -0.2032 -0.3048)
							(mid -0.275042 -0.275042)
							(end -0.3048 -0.2032)
						)
						(arc
							(start -0.3048 0.2032)
							(mid -0.275042 0.275042)
							(end -0.2032 0.3048)
						)
						(arc
							(start 0.2032 0.3048)
							(mid 0.275042 0.275042)
							(end 0.3048 0.2032)
						)
					)
					(width 0)
					(fill yes)
				)
			)
		)
	)
	(footprint ""
		(layer "F.Cu")
		(at 56.2864 -15.9004 -90)
		(property "Reference" "R45"
			(at 0 0 270)
			(layer "F.SilkS")
			(hide yes)
			(effects
				(font
					(size 1.27 1.27)
				)
			)
		)
		(property "Value" "4K7R2F-GP"
			(at 0.064008 -3.993896 270)
			(unlocked yes)
			(layer "F.Fab")
			(hide yes)
			(effects
				(font
					(size 1.016 1.016)
					(thickness 0.1524)
				)
			)
		)
		(property "Device Type" "R402H16"
			(at 0.064008 -5.517896 270)
			(unlocked yes)
			(layer "F.Fab")
			(hide yes)
			(effects
				(font
					(size 1.016 1.016)
					(thickness 0.1524)
				)
			)
		)
		(duplicate_pad_numbers_are_jumpers no)
		(fp_line
			(start -0.508 -0.9398)
			(end -0.508 0.9398)
			(stroke
				(width 0.1524)
				(type default)
			)
			(layer "F.SilkS")
		)
		(fp_line
			(start 0.508 -0.9398)
			(end -0.508 -0.9398)
			(stroke
				(width 0.1524)
				(type default)
			)
			(layer "F.SilkS")
		)
		(fp_rect
			(start -0.508 0.9398)
			(end 0.508 -0.9398)
			(stroke
				(width 0)
				(type default)
			)
			(fill no)
			(layer "F.CrtYd")
		)
		(fp_rect
			(start -0.508 0.9398)
			(end 0.508 -0.9398)
			(stroke
				(width 0)
				(type default)
			)
			(fill no)
			(layer "F.Fab")
		)
		(pad "1" smd custom
			(at 0 -0.4445 270)
			(size 0.1397 0.1397)
			(layers "F.Cu" "F.Mask" "F.Paste")
			(net "P3V3_STBY")
			(options
				(clearance outline)
				(anchor circle)
			)
			(primitives
				(gr_poly
					(pts
						(arc
							(start -0.1778 -0.2794)
							(mid -0.249642 -0.249642)
							(end -0.2794 -0.1778)
						)
						(arc
							(start -0.2794 0.1778)
							(mid -0.249642 0.249642)
							(end -0.1778 0.2794)
						)
						(arc
							(start 0.1778 0.2794)
							(mid 0.249642 0.249642)
							(end 0.2794 0.1778)
						)
						(arc
							(start 0.2794 -0.1778)
							(mid 0.249642 -0.249642)
							(end 0.1778 -0.2794)
						)
					)
					(width 0)
					(fill yes)
				)
			)
		)
		(pad "2" smd custom
			(at 0 0.4445 270)
			(size 0.1397 0.1397)
			(layers "F.Cu" "F.Mask" "F.Paste")
			(net "PCIE_SLOT2_PRSNT2_1_N")
			(options
				(clearance outline)
				(anchor circle)
			)
			(primitives
				(gr_poly
					(pts
						(arc
							(start -0.1778 -0.2794)
							(mid -0.249642 -0.249642)
							(end -0.2794 -0.1778)
						)
						(arc
							(start -0.2794 0.1778)
							(mid -0.249642 0.249642)
							(end -0.1778 0.2794)
						)
						(arc
							(start 0.1778 0.2794)
							(mid 0.249642 0.249642)
							(end 0.2794 0.1778)
						)
						(arc
							(start 0.2794 -0.1778)
							(mid 0.249642 -0.249642)
							(end 0.1778 -0.2794)
						)
					)
					(width 0)
					(fill yes)
				)
			)
		)
	)
	(footprint ""
		(layer "F.Cu")
		(at 26.5176 -27.686 -90)
		(property "Reference" "R94"
			(at 0 0 270)
			(layer "F.SilkS")
			(hide yes)
			(effects
				(font
					(size 1.27 1.27)
				)
			)
		)
		(property "Value" "10KR2F-2-GP"
			(at 0.064008 -3.993896 270)
			(unlocked yes)
			(layer "F.Fab")
			(hide yes)
			(effects
				(font
					(size 1.016 1.016)
					(thickness 0.1524)
				)
			)
		)
		(property "Device Type" "R402H16"
			(at 0.064008 -5.517896 270)
			(unlocked yes)
			(layer "F.Fab")
			(hide yes)
			(effects
				(font
					(size 1.016 1.016)
					(thickness 0.1524)
				)
			)
		)
		(duplicate_pad_numbers_are_jumpers no)
		(fp_line
			(start -0.508 -0.9398)
			(end -0.508 0.9398)
			(stroke
				(width 0.1524)
				(type default)
			)
			(layer "F.SilkS")
		)
		(fp_line
			(start 0.508 -0.9398)
			(end -0.508 -0.9398)
			(stroke
				(width 0.1524)
				(type default)
			)
			(layer "F.SilkS")
		)
		(fp_rect
			(start -0.508 0.9398)
			(end 0.508 -0.9398)
			(stroke
				(width 0)
				(type default)
			)
			(fill no)
			(layer "F.CrtYd")
		)
		(fp_rect
			(start -0.508 0.9398)
			(end 0.508 -0.9398)
			(stroke
				(width 0)
				(type default)
			)
			(fill no)
			(layer "F.Fab")
		)
		(pad "1" smd custom
			(at 0 -0.4445 270)
			(size 0.1397 0.1397)
			(layers "F.Cu" "F.Mask" "F.Paste")
			(net "P3V3_STBY")
			(options
				(clearance outline)
				(anchor circle)
			)
			(primitives
				(gr_poly
					(pts
						(arc
							(start -0.1778 -0.2794)
							(mid -0.249642 -0.249642)
							(end -0.2794 -0.1778)
						)
						(arc
							(start -0.2794 0.1778)
							(mid -0.249642 0.249642)
							(end -0.1778 0.2794)
						)
						(arc
							(start 0.1778 0.2794)
							(mid 0.249642 0.249642)
							(end 0.2794 0.1778)
						)
						(arc
							(start 0.2794 -0.1778)
							(mid 0.249642 -0.249642)
							(end 0.1778 -0.2794)
						)
					)
					(width 0)
					(fill yes)
				)
			)
		)
		(pad "2" smd custom
			(at 0 0.4445 270)
			(size 0.1397 0.1397)
			(layers "F.Cu" "F.Mask" "F.Paste")
			(net "SLOT3_VMONITOR_A0")
			(options
				(clearance outline)
				(anchor circle)
			)
			(primitives
				(gr_poly
					(pts
						(arc
							(start -0.1778 -0.2794)
							(mid -0.249642 -0.249642)
							(end -0.2794 -0.1778)
						)
						(arc
							(start -0.2794 0.1778)
							(mid -0.249642 0.249642)
							(end -0.1778 0.2794)
						)
						(arc
							(start 0.1778 0.2794)
							(mid 0.249642 0.249642)
							(end 0.2794 0.1778)
						)
						(arc
							(start 0.2794 -0.1778)
							(mid 0.249642 -0.249642)
							(end 0.1778 -0.2794)
						)
					)
					(width 0)
					(fill yes)
				)
			)
		)
	)
	(footprint ""
		(layer "F.Cu")
		(at 124.968 -0.0508)
		(property "Reference" "R141"
			(at 0 0 0)
			(layer "F.SilkS")
			(hide yes)
			(effects
				(font
					(size 1.27 1.27)
				)
			)
		)
		(property "Value" "10KR2F-2-GP"
			(at 0.064008 -3.993896 0)
			(unlocked yes)
			(layer "F.Fab")
			(hide yes)
			(effects
				(font
					(size 1.016 1.016)
					(thickness 0.1524)
				)
			)
		)
		(property "Device Type" "R402H16"
			(at 0.064008 -5.517896 0)
			(unlocked yes)
			(layer "F.Fab")
			(hide yes)
			(effects
				(font
					(size 1.016 1.016)
					(thickness 0.1524)
				)
			)
		)
		(duplicate_pad_numbers_are_jumpers no)
		(fp_line
			(start -0.508 -0.9398)
			(end -0.508 0.9398)
			(stroke
				(width 0.1524)
				(type default)
			)
			(layer "F.SilkS")
		)
		(fp_line
			(start 0.508 -0.9398)
			(end -0.508 -0.9398)
			(stroke
				(width 0.1524)
				(type default)
			)
			(layer "F.SilkS")
		)
		(fp_rect
			(start -0.508 0.9398)
			(end 0.508 -0.9398)
			(stroke
				(width 0)
				(type default)
			)
			(fill no)
			(layer "F.CrtYd")
		)
		(fp_rect
			(start -0.508 0.9398)
			(end 0.508 -0.9398)
			(stroke
				(width 0)
				(type default)
			)
			(fill no)
			(layer "F.Fab")
		)
		(pad "1" smd custom
			(at 0 -0.4445)
			(size 0.1397 0.1397)
			(layers "F.Cu" "F.Mask" "F.Paste")
			(net "GPIO_P_IO1_5")
			(options
				(clearance outline)
				(anchor circle)
			)
			(primitives
				(gr_poly
					(pts
						(arc
							(start -0.1778 -0.2794)
							(mid -0.249642 -0.249642)
							(end -0.2794 -0.1778)
						)
						(arc
							(start -0.2794 0.1778)
							(mid -0.249642 0.249642)
							(end -0.1778 0.2794)
						)
						(arc
							(start 0.1778 0.2794)
							(mid 0.249642 0.249642)
							(end 0.2794 0.1778)
						)
						(arc
							(start 0.2794 -0.1778)
							(mid 0.249642 -0.249642)
							(end 0.1778 -0.2794)
						)
					)
					(width 0)
					(fill yes)
				)
			)
		)
		(pad "2" smd custom
			(at 0 0.4445)
			(size 0.1397 0.1397)
			(layers "F.Cu" "F.Mask" "F.Paste")
			(net "GND")
			(options
				(clearance outline)
				(anchor circle)
			)
			(primitives
				(gr_poly
					(pts
						(arc
							(start -0.1778 -0.2794)
							(mid -0.249642 -0.249642)
							(end -0.2794 -0.1778)
						)
						(arc
							(start -0.2794 0.1778)
							(mid -0.249642 0.249642)
							(end -0.1778 0.2794)
						)
						(arc
							(start 0.1778 0.2794)
							(mid 0.249642 0.249642)
							(end 0.2794 0.1778)
						)
						(arc
							(start 0.2794 -0.1778)
							(mid 0.249642 -0.249642)
							(end 0.1778 -0.2794)
						)
					)
					(width 0)
					(fill yes)
				)
			)
		)
	)
	(footprint ""
		(layer "F.Cu")
		(at 132.08 -2.7432 90)
		(property "Reference" "C42"
			(at 0 0 90)
			(layer "F.SilkS")
			(hide yes)
			(effects
				(font
					(size 1.27 1.27)
				)
			)
		)
		(property "Value" "SCD1U16V2KX-3GP"
			(at 1.1811 -2.7051 90)
			(unlocked yes)
			(layer "F.Fab")
			(hide yes)
			(effects
				(font
					(size 1.016 1.016)
					(thickness 0.1524)
				)
			)
		)
		(property "Device Type" "C402H22"
			(at 1.1811 -4.2291 90)
			(unlocked yes)
			(layer "F.Fab")
			(hide yes)
			(effects
				(font
					(size 1.016 1.016)
					(thickness 0.1524)
				)
			)
		)
		(duplicate_pad_numbers_are_jumpers no)
		(fp_rect
			(start -0.4318 0.9525)
			(end 0.4318 -0.9525)
			(stroke
				(width 0)
				(type default)
			)
			(fill no)
			(layer "F.CrtYd")
		)
		(fp_rect
			(start -0.4318 0.9525)
			(end 0.4318 -0.9525)
			(stroke
				(width 0)
				(type default)
			)
			(fill no)
			(layer "F.Fab")
		)
		(pad "1" smd custom
			(at 0 -0.4445 90)
			(size 0.1524 0.1524)
			(layers "F.Cu" "F.Mask" "F.Paste")
			(net "P3V3_STBY")
			(options
				(clearance outline)
				(anchor circle)
			)
			(primitives
				(gr_poly
					(pts
						(arc
							(start 0.3048 -0.2032)
							(mid 0.275042 -0.275042)
							(end 0.2032 -0.3048)
						)
						(arc
							(start -0.2032 -0.3048)
							(mid -0.275042 -0.275042)
							(end -0.3048 -0.2032)
						)
						(arc
							(start -0.3048 0.2032)
							(mid -0.275042 0.275042)
							(end -0.2032 0.3048)
						)
						(arc
							(start 0.2032 0.3048)
							(mid 0.275042 0.275042)
							(end 0.3048 0.2032)
						)
					)
					(width 0)
					(fill yes)
				)
			)
		)
		(pad "2" smd custom
			(at 0 0.4445 90)
			(size 0.1524 0.1524)
			(layers "F.Cu" "F.Mask" "F.Paste")
			(net "GND")
			(options
				(clearance outline)
				(anchor circle)
			)
			(primitives
				(gr_poly
					(pts
						(arc
							(start 0.3048 -0.2032)
							(mid 0.275042 -0.275042)
							(end 0.2032 -0.3048)
						)
						(arc
							(start -0.2032 -0.3048)
							(mid -0.275042 -0.275042)
							(end -0.3048 -0.2032)
						)
						(arc
							(start -0.3048 0.2032)
							(mid -0.275042 0.275042)
							(end -0.2032 0.3048)
						)
						(arc
							(start 0.2032 0.3048)
							(mid 0.275042 0.275042)
							(end 0.3048 0.2032)
						)
					)
					(width 0)
					(fill yes)
				)
			)
		)
	)
	(footprint ""
		(layer "F.Cu")
		(at 16.4084 -32.0548 180)
		(property "Reference" "C29"
			(at 0 0 180)
			(layer "F.SilkS")
			(hide yes)
			(effects
				(font
					(size 1.27 1.27)
				)
			)
		)
		(property "Value" "SCD1U25V3KX-GP"
			(at 0 -2.8194 180)
			(unlocked yes)
			(layer "F.Fab")
			(hide yes)
			(effects
				(font
					(size 1.016 1.016)
					(thickness 0.1524)
				)
			)
		)
		(property "Device Type" "C603H36"
			(at 0 -4.3434 180)
			(unlocked yes)
			(layer "F.Fab")
			(hide yes)
			(effects
				(font
					(size 1.016 1.016)
					(thickness 0.1524)
				)
			)
		)
		(duplicate_pad_numbers_are_jumpers no)
		(fp_line
			(start 0.508 0)
			(end -0.508 0)
			(stroke
				(width 0.2032)
				(type default)
			)
			(layer "F.SilkS")
		)
		(fp_rect
			(start -0.5842 1.3335)
			(end 0.5842 -1.3335)
			(stroke
				(width 0)
				(type default)
			)
			(fill no)
			(layer "F.CrtYd")
		)
		(fp_rect
			(start -0.5842 1.3335)
			(end 0.5842 -1.3335)
			(stroke
				(width 0)
				(type default)
			)
			(fill no)
			(layer "F.Fab")
		)
		(pad "1" smd custom
			(at 0 -0.762 180)
			(size 0.2159 0.2159)
			(layers "F.Cu" "F.Mask" "F.Paste")
			(net "P12V_SLOT3")
			(options
				(clearance outline)
				(anchor circle)
			)
			(primitives
				(gr_poly
					(pts
						(arc
							(start -0.3302 -0.4318)
							(mid -0.402042 -0.402042)
							(end -0.4318 -0.3302)
						)
						(arc
							(start -0.4318 0.3302)
							(mid -0.402042 0.402042)
							(end -0.3302 0.4318)
						)
						(arc
							(start 0.3302 0.4318)
							(mid 0.402042 0.402042)
							(end 0.4318 0.3302)
						)
						(arc
							(start 0.4318 -0.3302)
							(mid 0.402042 -0.402042)
							(end 0.3302 -0.4318)
						)
					)
					(width 0)
					(fill yes)
				)
			)
		)
		(pad "2" smd custom
			(at 0 0.762 180)
			(size 0.2159 0.2159)
			(layers "F.Cu" "F.Mask" "F.Paste")
			(net "GND")
			(options
				(clearance outline)
				(anchor circle)
			)
			(primitives
				(gr_poly
					(pts
						(arc
							(start -0.3302 -0.4318)
							(mid -0.402042 -0.402042)
							(end -0.4318 -0.3302)
						)
						(arc
							(start -0.4318 0.3302)
							(mid -0.402042 0.402042)
							(end -0.3302 0.4318)
						)
						(arc
							(start 0.3302 0.4318)
							(mid 0.402042 0.402042)
							(end 0.4318 0.3302)
						)
						(arc
							(start 0.4318 -0.3302)
							(mid 0.402042 -0.402042)
							(end 0.3302 -0.4318)
						)
					)
					(width 0)
					(fill yes)
				)
			)
		)
	)
	(footprint ""
		(layer "F.Cu")
		(at 121.2596 -23.3934 -90)
		(property "Reference" "RU34"
			(at 0 0 270)
			(layer "F.SilkS")
			(hide yes)
			(effects
				(font
					(size 1.27 1.27)
				)
			)
		)
		(property "Value" "100KR2F-L1-GP"
			(at 0.064008 -3.993896 270)
			(unlocked yes)
			(layer "F.Fab")
			(hide yes)
			(effects
				(font
					(size 1.016 1.016)
					(thickness 0.1524)
				)
			)
		)
		(property "Device Type" "R402H16"
			(at 0.064008 -5.517896 270)
			(unlocked yes)
			(layer "F.Fab")
			(hide yes)
			(effects
				(font
					(size 1.016 1.016)
					(thickness 0.1524)
				)
			)
		)
		(duplicate_pad_numbers_are_jumpers no)
		(fp_line
			(start -0.508 -0.9398)
			(end -0.508 0.9398)
			(stroke
				(width 0.1524)
				(type default)
			)
			(layer "F.SilkS")
		)
		(fp_line
			(start 0.508 -0.9398)
			(end -0.508 -0.9398)
			(stroke
				(width 0.1524)
				(type default)
			)
			(layer "F.SilkS")
		)
		(fp_rect
			(start -0.508 0.9398)
			(end 0.508 -0.9398)
			(stroke
				(width 0)
				(type default)
			)
			(fill no)
			(layer "F.CrtYd")
		)
		(fp_rect
			(start -0.508 0.9398)
			(end 0.508 -0.9398)
			(stroke
				(width 0)
				(type default)
			)
			(fill no)
			(layer "F.Fab")
		)
		(pad "1" smd custom
			(at 0 -0.4445 270)
			(size 0.1397 0.1397)
			(layers "F.Cu" "F.Mask" "F.Paste")
			(net "SMDAT_USB_HUB_R")
			(options
				(clearance outline)
				(anchor circle)
			)
			(primitives
				(gr_poly
					(pts
						(arc
							(start -0.1778 -0.2794)
							(mid -0.249642 -0.249642)
							(end -0.2794 -0.1778)
						)
						(arc
							(start -0.2794 0.1778)
							(mid -0.249642 0.249642)
							(end -0.1778 0.2794)
						)
						(arc
							(start 0.1778 0.2794)
							(mid 0.249642 0.249642)
							(end 0.2794 0.1778)
						)
						(arc
							(start 0.2794 -0.1778)
							(mid 0.249642 -0.249642)
							(end 0.1778 -0.2794)
						)
					)
					(width 0)
					(fill yes)
				)
			)
		)
		(pad "2" smd custom
			(at 0 0.4445 270)
			(size 0.1397 0.1397)
			(layers "F.Cu" "F.Mask" "F.Paste")
			(net "GND")
			(options
				(clearance outline)
				(anchor circle)
			)
			(primitives
				(gr_poly
					(pts
						(arc
							(start -0.1778 -0.2794)
							(mid -0.249642 -0.249642)
							(end -0.2794 -0.1778)
						)
						(arc
							(start -0.2794 0.1778)
							(mid -0.249642 0.249642)
							(end -0.1778 0.2794)
						)
						(arc
							(start 0.1778 0.2794)
							(mid 0.249642 0.249642)
							(end 0.2794 0.1778)
						)
						(arc
							(start 0.2794 -0.1778)
							(mid 0.249642 -0.249642)
							(end 0.1778 -0.2794)
						)
					)
					(width 0)
					(fill yes)
				)
			)
		)
	)
)
